(kicad_pcb
	(version 20260206)
	(generator "pcbnew")
	(generator_version "10.0")
	(general
		(thickness 1.6)
		(legacy_teardrops no)
	)
	(paper "A4")
	(title_block
		(title "01162023_DA0F0TEBIF0_F0T_Expander_BD_F_brd_V02_OCP.brd")
		(comment 1 "Grand Teton / footprint 5622 of 9728 (PEX2), pads 1883-1999 of 2397")
	)
	(layers
		(0 "F.Cu" signal "TOP")
		(4 "In1.Cu" signal "GND")
		(6 "In2.Cu" signal "VCC")
		(8 "In3.Cu" signal "VCC1")
		(10 "In4.Cu" signal "GND1")
		(12 "In5.Cu" signal "IN1")
		(14 "In6.Cu" signal "GND2")
		(16 "In7.Cu" signal "IN2")
		(18 "In8.Cu" signal "GND3")
		(20 "In9.Cu" signal "IN3")
		(22 "In10.Cu" signal "GND4")
		(24 "In11.Cu" signal "IN4")
		(26 "In12.Cu" signal "GND5")
		(28 "In13.Cu" signal "IN5")
		(30 "In14.Cu" signal "GND6")
		(32 "In15.Cu" signal "IN6")
		(34 "In16.Cu" signal "GND7")
		(2 "B.Cu" signal "BOTTOM")
		(9 "F.Adhes" user "F.Adhesive")
		(11 "B.Adhes" user "B.Adhesive")
		(13 "F.Paste" user "Package Geometry/Pastemask Top")
		(15 "B.Paste" user "Package Geometry/Pastemask Bottom")
		(5 "F.SilkS" user "Ref Des/Silkscreen Top")
		(7 "B.SilkS" user "Ref Des/Silkscreen Bottom")
		(1 "F.Mask" user "Board Geometry/Soldermask Top")
		(3 "B.Mask" user "Board Geometry/Soldermask Bottom")
		(17 "Dwgs.User" user "User.Drawings")
		(19 "Cmts.User" user "User.Comments")
		(21 "Eco1.User" user "User.Eco1")
		(23 "Eco2.User" user "User.Eco2")
		(25 "Edge.Cuts" user "Board Geometry/Outline")
		(27 "Margin" user)
		(31 "F.CrtYd" user "Package Geometry/Place Bound Top")
		(29 "B.CrtYd" user "Package Geometry/Place Bound Bottom")
		(35 "F.Fab" user "Ref Des/Assembly Top")
		(33 "B.Fab" user "Ref Des/Assembly Bottom")
	)
	(footprint ""
		(layer "F.Cu")
		(at 291.84981 -295.89984)
		(property "Reference" "PEX2"
			(at -3.35153 35.56762 0)
			(unlocked yes)
			(layer "F.SilkS")
			(effects
				(font
					(size 2.032 1.524)
					(thickness 0.1524)
				)
				(justify left)
			)
		)
		(property "Value" ""
			(at 0 0 0)
			(layer "F.Fab")
			(effects
				(font
					(size 1.27 1.27)
				)
			)
		)
		(duplicate_pad_numbers_are_jumpers no)
		(pad "K25" smd circle
			(at 0 -14.249908)
			(size 0.4572 0.4572)
			(layers "F.Cu" "F.Mask" "F.Paste")
			(net "GND")
		)
		(pad "K26" smd circle
			(at 0.94996 -14.249908)
			(size 0.4572 0.4572)
			(layers "F.Cu" "F.Mask" "F.Paste")
			(net "GND")
		)
		(pad "K27" smd circle
			(at 1.89992 -14.249908)
			(size 0.4572 0.4572)
			(layers "F.Cu" "F.Mask" "F.Paste")
			(net "GND")
		)
		(pad "K28" smd circle
			(at 2.84988 -14.249908)
			(size 0.4572 0.4572)
			(layers "F.Cu" "F.Mask" "F.Paste")
			(net "GND")
		)
		(pad "K29" smd circle
			(at 3.800094 -14.249908)
			(size 0.4572 0.4572)
			(layers "F.Cu" "F.Mask" "F.Paste")
			(net "GND")
		)
		(pad "K30" smd circle
			(at 4.750054 -14.249908)
			(size 0.4572 0.4572)
			(layers "F.Cu" "F.Mask" "F.Paste")
			(net "GND")
		)
		(pad "K31" smd circle
			(at 5.700014 -14.249908)
			(size 0.4572 0.4572)
			(layers "F.Cu" "F.Mask" "F.Paste")
			(net "GND")
		)
		(pad "K32" smd circle
			(at 6.649974 -14.249908)
			(size 0.4572 0.4572)
			(layers "F.Cu" "F.Mask" "F.Paste")
			(net "GND")
		)
		(pad "K33" smd circle
			(at 7.599934 -14.249908)
			(size 0.4572 0.4572)
			(layers "F.Cu" "F.Mask" "F.Paste")
			(net "GND")
		)
		(pad "K34" smd circle
			(at 8.549894 -14.249908)
			(size 0.4572 0.4572)
			(layers "F.Cu" "F.Mask" "F.Paste")
			(net "GND")
		)
		(pad "K35" smd circle
			(at 9.500108 -14.249908)
			(size 0.4572 0.4572)
			(layers "F.Cu" "F.Mask" "F.Paste")
			(net "GND")
		)
		(pad "K36" smd circle
			(at 10.450068 -14.249908)
			(size 0.4572 0.4572)
			(layers "F.Cu" "F.Mask" "F.Paste")
			(net "GND")
		)
		(pad "K37" smd circle
			(at 11.400028 -14.249908)
			(size 0.4572 0.4572)
			(layers "F.Cu" "F.Mask" "F.Paste")
			(net "GND")
		)
		(pad "K38" smd circle
			(at 12.349988 -14.249908)
			(size 0.4572 0.4572)
			(layers "F.Cu" "F.Mask" "F.Paste")
			(net "GND")
		)
		(pad "K39" smd circle
			(at 13.299948 -14.249908)
			(size 0.4572 0.4572)
			(layers "F.Cu" "F.Mask" "F.Paste")
			(net "GND")
		)
		(pad "K40" smd circle
			(at 14.249908 -14.249908)
			(size 0.4572 0.4572)
			(layers "F.Cu" "F.Mask" "F.Paste")
			(net "GND")
		)
		(pad "K41" smd circle
			(at 15.200122 -14.249908)
			(size 0.4572 0.4572)
			(layers "F.Cu" "F.Mask" "F.Paste")
			(net "GND")
		)
		(pad "K42" smd circle
			(at 16.150082 -14.249908)
			(size 0.4572 0.4572)
			(layers "F.Cu" "F.Mask" "F.Paste")
			(net "GND")
		)
		(pad "K43" smd circle
			(at 17.100042 -14.249908)
			(size 0.4572 0.4572)
			(layers "F.Cu" "F.Mask" "F.Paste")
			(net "GND")
		)
		(pad "K44" smd circle
			(at 18.050002 -14.249908)
			(size 0.4572 0.4572)
			(layers "F.Cu" "F.Mask" "F.Paste")
			(net "GND")
		)
		(pad "K45" smd circle
			(at 18.999962 -14.249908)
			(size 0.4572 0.4572)
			(layers "F.Cu" "F.Mask" "F.Paste")
			(net "GND")
		)
		(pad "K46" smd circle
			(at 19.949922 -14.249908)
			(size 0.4572 0.4572)
			(layers "F.Cu" "F.Mask" "F.Paste")
			(net "GND")
		)
		(pad "K47" smd circle
			(at 20.899882 -14.249908)
			(size 0.4572 0.4572)
			(layers "F.Cu" "F.Mask" "F.Paste")
			(net "GND")
		)
		(pad "K48" smd circle
			(at 21.850096 -14.249908)
			(size 0.4572 0.4572)
			(layers "F.Cu" "F.Mask" "F.Paste")
			(net "P5E_PEX2_STN4_RX_DP<70>")
		)
		(pad "K49" smd circle
			(at 22.800056 -14.249908)
			(size 0.4572 0.4572)
			(layers "F.Cu" "F.Mask" "F.Paste")
			(net "P5E_PEX2_STN4_RX_DN<70>")
		)
		(pad "L1" smd circle
			(at -22.800056 -13.299948)
			(size 0.4572 0.4572)
			(layers "F.Cu" "F.Mask" "F.Paste")
			(net "GND")
		)
		(pad "L2" smd circle
			(at -21.850096 -13.299948)
			(size 0.4572 0.4572)
			(layers "F.Cu" "F.Mask" "F.Paste")
			(net "GND")
		)
		(pad "L3" smd circle
			(at -20.899882 -13.299948)
			(size 0.4572 0.4572)
			(layers "F.Cu" "F.Mask" "F.Paste")
			(net "P5E_PEX2_STN7_RX_DN<120>")
		)
		(pad "L4" smd circle
			(at -19.949922 -13.299948)
			(size 0.4572 0.4572)
			(layers "F.Cu" "F.Mask" "F.Paste")
			(net "P5E_PEX2_STN7_RX_DP<120>")
		)
		(pad "L5" smd circle
			(at -18.999962 -13.299948)
			(size 0.4572 0.4572)
			(layers "F.Cu" "F.Mask" "F.Paste")
			(net "GND")
		)
		(pad "L6" smd circle
			(at -18.050002 -13.299948)
			(size 0.4572 0.4572)
			(layers "F.Cu" "F.Mask" "F.Paste")
			(net "P5E_PEX2_STN7_TX_DN<120>")
		)
		(pad "L7" smd circle
			(at -17.100042 -13.299948)
			(size 0.4572 0.4572)
			(layers "F.Cu" "F.Mask" "F.Paste")
			(net "P5E_PEX2_STN7_TX_DP<120>")
		)
		(pad "L8" smd circle
			(at -16.150082 -13.299948)
			(size 0.4572 0.4572)
			(layers "F.Cu" "F.Mask" "F.Paste")
			(net "GND")
		)
		(pad "L9" smd circle
			(at -15.200122 -13.299948)
			(size 0.4572 0.4572)
			(layers "F.Cu" "F.Mask" "F.Paste")
			(net "GND")
		)
		(pad "L10" smd circle
			(at -14.249908 -13.299948)
			(size 0.4572 0.4572)
			(layers "F.Cu" "F.Mask" "F.Paste")
			(net "GND")
		)
		(pad "L11" smd circle
			(at -13.299948 -13.299948)
			(size 0.4572 0.4572)
			(layers "F.Cu" "F.Mask" "F.Paste")
			(net "GND")
		)
		(pad "L12" smd circle
			(at -12.349988 -13.299948)
			(size 0.4572 0.4572)
			(layers "F.Cu" "F.Mask" "F.Paste")
			(net "PEX2_DBG_MODE0")
		)
		(pad "L13" smd circle
			(at -11.400028 -13.299948)
			(size 0.4572 0.4572)
			(layers "F.Cu" "F.Mask" "F.Paste")
			(net "PEX2_DBG_MODE1")
		)
		(pad "L14" smd circle
			(at -10.450068 -13.299948)
			(size 0.4572 0.4572)
			(layers "F.Cu" "F.Mask" "F.Paste")
			(net "GND")
		)
		(pad "L15" smd circle
			(at -9.500108 -13.299948)
			(size 0.4572 0.4572)
			(layers "F.Cu" "F.Mask" "F.Paste")
			(net "PU_PEX2_ATPG_MODE_L")
		)
		(pad "L16" smd circle
			(at -8.549894 -13.299948)
			(size 0.4572 0.4572)
			(layers "F.Cu" "F.Mask" "F.Paste")
			(net "PU_PEX2_PAD_TRI_L")
		)
		(pad "L17" smd circle
			(at -7.599934 -13.299948)
			(size 0.4572 0.4572)
			(layers "F.Cu" "F.Mask" "F.Paste")
			(net "TP_PEX2_TDI")
		)
		(pad "L18" smd circle
			(at -6.649974 -13.299948)
			(size 0.4572 0.4572)
			(layers "F.Cu" "F.Mask" "F.Paste")
			(net "PEX2_DBG_SEL0")
		)
		(pad "L19" smd circle
			(at -5.700014 -13.299948)
			(size 0.4572 0.4572)
			(layers "F.Cu" "F.Mask" "F.Paste")
			(net "TP_PEX2_TDO")
		)
		(pad "L20" smd circle
			(at -4.750054 -13.299948)
			(size 0.4572 0.4572)
			(layers "F.Cu" "F.Mask" "F.Paste")
			(net "PU_PEX2_TR_TCK")
		)
		(pad "L21" smd circle
			(at -3.800094 -13.299948)
			(size 0.4572 0.4572)
			(layers "F.Cu" "F.Mask" "F.Paste")
			(net "GND")
		)
		(pad "L22" smd circle
			(at -2.84988 -13.299948)
			(size 0.4572 0.4572)
			(layers "F.Cu" "F.Mask" "F.Paste")
			(net "Net_5379")
		)
		(pad "L23" smd circle
			(at -1.89992 -13.299948)
			(size 0.4572 0.4572)
			(layers "F.Cu" "F.Mask" "F.Paste")
			(net "Net_5383")
		)
		(pad "L24" smd circle
			(at -0.94996 -13.299948)
			(size 0.4572 0.4572)
			(layers "F.Cu" "F.Mask" "F.Paste")
			(net "Net_5378")
		)
		(pad "L25" smd circle
			(at 0 -13.299948)
			(size 0.4572 0.4572)
			(layers "F.Cu" "F.Mask" "F.Paste")
			(net "PEX2_SPARE5")
		)
		(pad "L26" smd circle
			(at 0.94996 -13.299948)
			(size 0.4572 0.4572)
			(layers "F.Cu" "F.Mask" "F.Paste")
			(net "PU_PEX2_SIO_BLINK")
		)
		(pad "L27" smd circle
			(at 1.89992 -13.299948)
			(size 0.4572 0.4572)
			(layers "F.Cu" "F.Mask" "F.Paste")
			(net "PEX2_SPARE2")
		)
		(pad "L28" smd circle
			(at 2.84988 -13.299948)
			(size 0.4572 0.4572)
			(layers "F.Cu" "F.Mask" "F.Paste")
			(net "PEX2_SPARE6")
		)
		(pad "L29" smd circle
			(at 3.800094 -13.299948)
			(size 0.4572 0.4572)
			(layers "F.Cu" "F.Mask" "F.Paste")
			(net "Net_5368")
		)
		(pad "L30" smd circle
			(at 4.750054 -13.299948)
			(size 0.4572 0.4572)
			(layers "F.Cu" "F.Mask" "F.Paste")
			(net "PEX2_SPARE1")
		)
		(pad "L31" smd circle
			(at 5.700014 -13.299948)
			(size 0.4572 0.4572)
			(layers "F.Cu" "F.Mask" "F.Paste")
			(net "Net_5372")
		)
		(pad "L32" smd circle
			(at 6.649974 -13.299948)
			(size 0.4572 0.4572)
			(layers "F.Cu" "F.Mask" "F.Paste")
			(net "PEX2_SPARE3")
		)
		(pad "L33" smd circle
			(at 7.599934 -13.299948)
			(size 0.4572 0.4572)
			(layers "F.Cu" "F.Mask" "F.Paste")
			(net "Net_5364")
		)
		(pad "L34" smd circle
			(at 8.549894 -13.299948)
			(size 0.4572 0.4572)
			(layers "F.Cu" "F.Mask" "F.Paste")
			(net "SMB_PEX2_SLAVE1_SCL")
		)
		(pad "L35" smd circle
			(at 9.500108 -13.299948)
			(size 0.4572 0.4572)
			(layers "F.Cu" "F.Mask" "F.Paste")
			(net "Net_5361")
		)
		(pad "L36" smd circle
			(at 10.450068 -13.299948)
			(size 0.4572 0.4572)
			(layers "F.Cu" "F.Mask" "F.Paste")
			(net "Net_5391")
		)
		(pad "L37" smd circle
			(at 11.400028 -13.299948)
			(size 0.4572 0.4572)
			(layers "F.Cu" "F.Mask" "F.Paste")
			(net "PEX2_EXT_GPIO_LATCH_N")
		)
		(pad "L38" smd circle
			(at 12.349988 -13.299948)
			(size 0.4572 0.4572)
			(layers "F.Cu" "F.Mask" "F.Paste")
			(net "Net_5388")
		)
		(pad "L39" smd circle
			(at 13.299948 -13.299948)
			(size 0.4572 0.4572)
			(layers "F.Cu" "F.Mask" "F.Paste")
			(net "SMB_PEX2_SLAVE_SDA")
		)
		(pad "L40" smd circle
			(at 14.249908 -13.299948)
			(size 0.4572 0.4572)
			(layers "F.Cu" "F.Mask" "F.Paste")
			(net "GND")
		)
		(pad "L41" smd circle
			(at 15.200122 -13.299948)
			(size 0.4572 0.4572)
			(layers "F.Cu" "F.Mask" "F.Paste")
			(net "GND")
		)
		(pad "L42" smd circle
			(at 16.150082 -13.299948)
			(size 0.4572 0.4572)
			(layers "F.Cu" "F.Mask" "F.Paste")
			(net "GND")
		)
		(pad "L43" smd circle
			(at 17.100042 -13.299948)
			(size 0.4572 0.4572)
			(layers "F.Cu" "F.Mask" "F.Paste")
			(net "P5E_PEX2_STN4_TX_DP<69>")
		)
		(pad "L44" smd circle
			(at 18.050002 -13.299948)
			(size 0.4572 0.4572)
			(layers "F.Cu" "F.Mask" "F.Paste")
			(net "P5E_PEX2_STN4_TX_DN<69>")
		)
		(pad "L45" smd circle
			(at 18.999962 -13.299948)
			(size 0.4572 0.4572)
			(layers "F.Cu" "F.Mask" "F.Paste")
			(net "GND")
		)
		(pad "L46" smd circle
			(at 19.949922 -13.299948)
			(size 0.4572 0.4572)
			(layers "F.Cu" "F.Mask" "F.Paste")
			(net "P5E_PEX2_STN4_RX_DP<69>")
		)
		(pad "L47" smd circle
			(at 20.899882 -13.299948)
			(size 0.4572 0.4572)
			(layers "F.Cu" "F.Mask" "F.Paste")
			(net "P5E_PEX2_STN4_RX_DN<69>")
		)
		(pad "L48" smd circle
			(at 21.850096 -13.299948)
			(size 0.4572 0.4572)
			(layers "F.Cu" "F.Mask" "F.Paste")
			(net "GND")
		)
		(pad "L49" smd circle
			(at 22.800056 -13.299948)
			(size 0.4572 0.4572)
			(layers "F.Cu" "F.Mask" "F.Paste")
			(net "GND")
		)
		(pad "M1" smd circle
			(at -22.800056 -12.349988)
			(size 0.4572 0.4572)
			(layers "F.Cu" "F.Mask" "F.Paste")
			(net "P5E_PEX2_STN7_RX_DN<119>")
		)
		(pad "M2" smd circle
			(at -21.850096 -12.349988)
			(size 0.4572 0.4572)
			(layers "F.Cu" "F.Mask" "F.Paste")
			(net "P5E_PEX2_STN7_RX_DP<119>")
		)
		(pad "M3" smd circle
			(at -20.899882 -12.349988)
			(size 0.4572 0.4572)
			(layers "F.Cu" "F.Mask" "F.Paste")
			(net "GND")
		)
		(pad "M4" smd circle
			(at -19.949922 -12.349988)
			(size 0.4572 0.4572)
			(layers "F.Cu" "F.Mask" "F.Paste")
			(net "GND")
		)
		(pad "M5" smd circle
			(at -18.999962 -12.349988)
			(size 0.4572 0.4572)
			(layers "F.Cu" "F.Mask" "F.Paste")
			(net "GND")
		)
		(pad "M6" smd circle
			(at -18.050002 -12.349988)
			(size 0.4572 0.4572)
			(layers "F.Cu" "F.Mask" "F.Paste")
			(net "GND")
		)
		(pad "M7" smd circle
			(at -17.100042 -12.349988)
			(size 0.4572 0.4572)
			(layers "F.Cu" "F.Mask" "F.Paste")
			(net "GND")
		)
		(pad "M8" smd circle
			(at -16.150082 -12.349988)
			(size 0.4572 0.4572)
			(layers "F.Cu" "F.Mask" "F.Paste")
			(net "P5E_PEX2_STN7_TX_DN<119>")
		)
		(pad "M9" smd circle
			(at -15.200122 -12.349988)
			(size 0.4572 0.4572)
			(layers "F.Cu" "F.Mask" "F.Paste")
			(net "P5E_PEX2_STN7_TX_DP<119>")
		)
		(pad "M10" smd circle
			(at -14.249908 -12.349988)
			(size 0.4572 0.4572)
			(layers "F.Cu" "F.Mask" "F.Paste")
			(net "GND")
		)
		(pad "M11" smd circle
			(at -13.299948 -12.349988)
			(size 0.4572 0.4572)
			(layers "F.Cu" "F.Mask" "F.Paste")
			(net "GND")
		)
		(pad "M12" smd circle
			(at -12.349988 -12.349988)
			(size 0.4572 0.4572)
			(layers "F.Cu" "F.Mask" "F.Paste")
			(net "GND")
		)
		(pad "M13" smd circle
			(at -11.400028 -12.349988)
			(size 0.4572 0.4572)
			(layers "F.Cu" "F.Mask" "F.Paste")
			(net "IRQ_PEX2_CLKREQ_INT_N")
		)
		(pad "M14" smd circle
			(at -10.450068 -12.349988)
			(size 0.4572 0.4572)
			(layers "F.Cu" "F.Mask" "F.Paste")
			(net "GND")
		)
		(pad "M15" smd circle
			(at -9.500108 -12.349988)
			(size 0.4572 0.4572)
			(layers "F.Cu" "F.Mask" "F.Paste")
			(net "TP_PEX2_TCK")
		)
		(pad "M16" smd circle
			(at -8.549894 -12.349988)
			(size 0.4572 0.4572)
			(layers "F.Cu" "F.Mask" "F.Paste")
			(net "PEX2_DFT_IDDT")
		)
		(pad "M17" smd circle
			(at -7.599934 -12.349988)
			(size 0.4572 0.4572)
			(layers "F.Cu" "F.Mask" "F.Paste")
			(net "RST_PEX2_SYS_N")
		)
		(pad "M18" smd circle
			(at -6.649974 -12.349988)
			(size 0.4572 0.4572)
			(layers "F.Cu" "F.Mask" "F.Paste")
			(net "TP_PEX2_TRST_L")
		)
		(pad "M19" smd circle
			(at -5.700014 -12.349988)
			(size 0.4572 0.4572)
			(layers "F.Cu" "F.Mask" "F.Paste")
			(net "PEX2_DBG_SEL1")
		)
		(pad "M20" smd circle
			(at -4.750054 -12.349988)
			(size 0.4572 0.4572)
			(layers "F.Cu" "F.Mask" "F.Paste")
			(net "TP_PEX2_TMS")
		)
		(pad "M21" smd circle
			(at -3.800094 -12.349988)
			(size 0.4572 0.4572)
			(layers "F.Cu" "F.Mask" "F.Paste")
			(net "GND")
		)
		(pad "M22" smd circle
			(at -2.84988 -12.349988)
			(size 0.4572 0.4572)
			(layers "F.Cu" "F.Mask" "F.Paste")
			(net "Net_5381")
		)
		(pad "M23" smd circle
			(at -1.89992 -12.349988)
			(size 0.4572 0.4572)
			(layers "F.Cu" "F.Mask" "F.Paste")
			(net "Net_5382")
		)
		(pad "M24" smd circle
			(at -0.94996 -12.349988)
			(size 0.4572 0.4572)
			(layers "F.Cu" "F.Mask" "F.Paste")
			(net "Net_5384")
		)
		(pad "M25" smd circle
			(at 0 -12.349988)
			(size 0.4572 0.4572)
			(layers "F.Cu" "F.Mask" "F.Paste")
			(net "PEX2_SPARE4")
		)
		(pad "M26" smd circle
			(at 0.94996 -12.349988)
			(size 0.4572 0.4572)
			(layers "F.Cu" "F.Mask" "F.Paste")
			(net "PEX2_SPARE0")
		)
		(pad "M27" smd circle
			(at 1.89992 -12.349988)
			(size 0.4572 0.4572)
			(layers "F.Cu" "F.Mask" "F.Paste")
			(net "PEX2_SPARE7")
		)
		(pad "M28" smd circle
			(at 2.84988 -12.349988)
			(size 0.4572 0.4572)
			(layers "F.Cu" "F.Mask" "F.Paste")
			(net "I2C0_PEX2_SHPC_SDA")
		)
		(pad "M29" smd circle
			(at 3.800094 -12.349988)
			(size 0.4572 0.4572)
			(layers "F.Cu" "F.Mask" "F.Paste")
			(net "I2C0_PEX2_SHPC_SCL")
		)
		(pad "M30" smd circle
			(at 4.750054 -12.349988)
			(size 0.4572 0.4572)
			(layers "F.Cu" "F.Mask" "F.Paste")
			(net "Net_5362")
		)
		(pad "M31" smd circle
			(at 5.700014 -12.349988)
			(size 0.4572 0.4572)
			(layers "F.Cu" "F.Mask" "F.Paste")
			(net "Net_5363")
		)
		(pad "M32" smd circle
			(at 6.649974 -12.349988)
			(size 0.4572 0.4572)
			(layers "F.Cu" "F.Mask" "F.Paste")
			(net "Net_5373")
		)
		(pad "M33" smd circle
			(at 7.599934 -12.349988)
			(size 0.4572 0.4572)
			(layers "F.Cu" "F.Mask" "F.Paste")
			(net "Net_5367")
		)
		(pad "M34" smd circle
			(at 8.549894 -12.349988)
			(size 0.4572 0.4572)
			(layers "F.Cu" "F.Mask" "F.Paste")
			(net "Net_5371")
		)
		(pad "M35" smd circle
			(at 9.500108 -12.349988)
			(size 0.4572 0.4572)
			(layers "F.Cu" "F.Mask" "F.Paste")
			(net "I2C0_PEX2_SCL")
		)
		(pad "M36" smd circle
			(at 10.450068 -12.349988)
			(size 0.4572 0.4572)
			(layers "F.Cu" "F.Mask" "F.Paste")
			(net "Net_5390")
		)
		(pad "M37" smd circle
			(at 11.400028 -12.349988)
			(size 0.4572 0.4572)
			(layers "F.Cu" "F.Mask" "F.Paste")
			(net "Net_5389")
		)
		(pad "M38" smd circle
			(at 12.349988 -12.349988)
			(size 0.4572 0.4572)
			(layers "F.Cu" "F.Mask" "F.Paste")
			(net "SMB_PEX2_SLAVE1_SDA")
		)
		(pad "M39" smd circle
			(at 13.299948 -12.349988)
			(size 0.4572 0.4572)
			(layers "F.Cu" "F.Mask" "F.Paste")
			(net "I2C0_PEX2_SDA")
		)
		(pad "M40" smd circle
			(at 14.249908 -12.349988)
			(size 0.4572 0.4572)
			(layers "F.Cu" "F.Mask" "F.Paste")
			(net "GND")
		)
		(pad "M41" smd circle
			(at 15.200122 -12.349988)
			(size 0.4572 0.4572)
			(layers "F.Cu" "F.Mask" "F.Paste")
			(net "P5E_PEX2_STN4_TX_DP<68>")
		)
		(pad "M42" smd circle
			(at 16.150082 -12.349988)
			(size 0.4572 0.4572)
			(layers "F.Cu" "F.Mask" "F.Paste")
			(net "P5E_PEX2_STN4_TX_DN<68>")
		)
		(pad "M43" smd circle
			(at 17.100042 -12.349988)
			(size 0.4572 0.4572)
			(layers "F.Cu" "F.Mask" "F.Paste")
			(net "GND")
		)
	)
)
